(kicad_pcb
	(version 20241229)
	(generator "pcbnew")
	(generator_version "9.0")
	(general
		(thickness 1.6642)
		(legacy_teardrops no)
	)
	(paper "A3")
	(title_block
		(title "PolarFire SoM")
		(date "2025-07-22")
		(rev "1.1.4")
		(company "Antmicro Ltd")
		(comment 1 "www.antmicro.com")
		(comment 9 "footprints 165-169 of 470")
	)
	(layers
		(0 "F.Cu" mixed)
		(4 "In1.Cu" power)
		(6 "In2.Cu" signal)
		(8 "In3.Cu" power)
		(10 "In4.Cu" signal)
		(12 "In5.Cu" power)
		(14 "In6.Cu" power)
		(16 "In7.Cu" signal)
		(18 "In8.Cu" power)
		(20 "In9.Cu" signal)
		(22 "In10.Cu" power)
		(24 "In11.Cu" signal)
		(26 "In12.Cu" signal)
		(2 "B.Cu" mixed)
		(9 "F.Adhes" user "F.Adhesive")
		(11 "B.Adhes" user "B.Adhesive")
		(13 "F.Paste" user)
		(15 "B.Paste" user)
		(5 "F.SilkS" user "F.Silkscreen")
		(7 "B.SilkS" user "B.Silkscreen")
		(1 "F.Mask" user)
		(3 "B.Mask" user)
		(17 "Dwgs.User" user "User.Drawings")
		(19 "Cmts.User" user "User.Comments")
		(21 "Eco1.User" user "User.Eco1")
		(23 "Eco2.User" user "User.Eco2")
		(25 "Edge.Cuts" user)
		(27 "Margin" user)
		(31 "F.CrtYd" user "F.Courtyard")
		(29 "B.CrtYd" user "B.Courtyard")
		(35 "F.Fab" user)
		(33 "B.Fab" user)
	)
	(footprint "antmicro-footprints:R_0402_1005Metric"
		(layer "B.Cu")
		(at 185.325 154.43 90)
		(descr "Resistor SMD 0402")
		(tags "resistor SMD 0402")
		(property "Reference" "R61"
			(at 1.225 -4.975 270)
			(layer "B.SilkS")
			(effects
				(font
					(size 0.7 0.7)
					(thickness 0.15)
				)
				(justify left bottom mirror)
			)
		)
		(property "Value" "R_1M_0402"
			(at -1.011843 -1.772047 270)
			(layer "B.Fab")
			(hide yes)
			(effects
				(font
					(size 0.7 0.7)
					(thickness 0.15)
				)
				(justify left bottom mirror)
			)
		)
		(property "Datasheet" "https://www.bourns.com/docs/product-datasheets/cr.pdf"
			(at 0 0 90)
			(layer "F.Fab")
			(hide yes)
			(effects
				(font
					(size 1.27 1.27)
					(thickness 0.15)
				)
			)
		)
		(property "Description" "SMD Chip Resistor, 1 Mohm, ± 1%, 62.5 mW, 0402 [1005 Metric], Thick Film, General Purpose"
			(at 0 0 90)
			(layer "F.Fab")
			(hide yes)
			(effects
				(font
					(size 1.27 1.27)
					(thickness 0.15)
				)
			)
		)
		(property "Author" "Antmicro"
			(at 339.755 -30.895 0)
			(layer "B.Fab")
			(hide yes)
			(effects
				(font
					(size 1 1)
					(thickness 0.15)
				)
				(justify mirror)
			)
		)
		(property "License" "Apache-2.0"
			(at 339.755 -30.895 0)
			(layer "B.Fab")
			(hide yes)
			(effects
				(font
					(size 1 1)
					(thickness 0.15)
				)
				(justify mirror)
			)
		)
		(property "MPN" "CR0402-FX-1004GLF"
			(at 339.755 -30.895 0)
			(layer "B.Fab")
			(hide yes)
			(effects
				(font
					(size 1 1)
					(thickness 0.15)
				)
				(justify mirror)
			)
		)
		(property "Manufacturer" "Bourns"
			(at 339.755 -30.895 0)
			(layer "B.Fab")
			(hide yes)
			(effects
				(font
					(size 1 1)
					(thickness 0.15)
				)
				(justify mirror)
			)
		)
		(property "Public" ""
			(at 339.755 -30.895 0)
			(layer "B.Fab")
			(hide yes)
			(effects
				(font
					(size 1 1)
					(thickness 0.15)
				)
				(justify mirror)
			)
		)
		(property "Tolerance" "1%"
			(at 339.755 -30.895 0)
			(layer "B.Fab")
			(hide yes)
			(effects
				(font
					(size 1 1)
					(thickness 0.15)
				)
				(justify mirror)
			)
		)
		(property "Val" "1M"
			(at 339.755 -30.895 0)
			(layer "B.Fab")
			(hide yes)
			(effects
				(font
					(size 1 1)
					(thickness 0.15)
				)
				(justify mirror)
			)
		)
		(sheetname "/Bottom Connector/")
		(sheetfile "bottom-connector.kicad_sch")
		(attr smd)
		(fp_rect
			(start -0.925 0.47)
			(end 0.925 -0.47)
			(stroke
				(width 0.05)
				(type default)
			)
			(fill no)
			(layer "B.CrtYd")
		)
		(fp_rect
			(start -0.5 0.25)
			(end 0.5 -0.25)
			(stroke
				(width 0.15)
				(type solid)
			)
			(fill no)
			(layer "B.Fab")
		)
		(fp_text user "License: Apache-2.0"
			(at -0.95 -5.169 270)
			(layer "B.Fab")
			(effects
				(font
					(size 0.7 0.7)
					(thickness 0.15)
				)
				(justify left bottom mirror)
			)
		)
		(fp_text user "Author: Antmicro"
			(at -0.95 -4.169 270)
			(layer "B.Fab")
			(effects
				(font
					(size 0.7 0.7)
					(thickness 0.15)
				)
				(justify left bottom mirror)
			)
		)
		(fp_text user "${REFERENCE}"
			(at -0.95 -3.168 270)
			(layer "B.Fab")
			(effects
				(font
					(size 0.7 0.7)
					(thickness 0.15)
				)
				(justify left bottom mirror)
			)
		)
		(pad "1" smd roundrect
			(at -0.48 0 90)
			(size 0.59 0.64)
			(layers "B.Cu" "B.Mask" "B.Paste")
			(roundrect_rratio 0.25)
			(net 417 "GND")
			(pintype "passive")
		)
		(pad "2" smd roundrect
			(at 0.48 0 90)
			(size 0.59 0.64)
			(layers "B.Cu" "B.Mask" "B.Paste")
			(roundrect_rratio 0.25)
			(net 411 "Net-(Q3-BIAS)")
			(pintype "passive")
		)
	)
	(footprint "antmicro-footprints:R_0402_1005Metric"
		(layer "B.Cu")
		(at 210.1925 130.35)
		(descr "Resistor SMD 0402")
		(tags "resistor SMD 0402")
		(property "Reference" "R36"
			(at -0.8425 0.628 180)
			(layer "B.SilkS")
			(effects
				(font
					(size 0.7 0.7)
					(thickness 0.15)
				)
				(justify left bottom mirror)
			)
		)
		(property "Value" "R_49k9_0402"
			(at -1.011843 -1.772047 180)
			(layer "B.Fab")
			(hide yes)
			(effects
				(font
					(size 0.7 0.7)
					(thickness 0.15)
				)
				(justify left bottom mirror)
			)
		)
		(property "Datasheet" "https://www.bourns.com/docs/product-datasheets/cr.pdf"
			(at 0 0 0)
			(layer "F.Fab")
			(hide yes)
			(effects
				(font
					(size 1.27 1.27)
					(thickness 0.15)
				)
			)
		)
		(property "Description" "SMD Chip Resistor, 49.9 kohm, ± 1%, 63 mW, 0402 [1005 Metric], Thick Film, General Purpose"
			(at 0 0 0)
			(layer "F.Fab")
			(hide yes)
			(effects
				(font
					(size 1.27 1.27)
					(thickness 0.15)
				)
			)
		)
		(property "Author" "Antmicro"
			(at 0 0 0)
			(layer "B.Fab")
			(hide yes)
			(effects
				(font
					(size 1 1)
					(thickness 0.15)
				)
				(justify mirror)
			)
		)
		(property "License" "Apache-2.0"
			(at 0 0 0)
			(layer "B.Fab")
			(hide yes)
			(effects
				(font
					(size 1 1)
					(thickness 0.15)
				)
				(justify mirror)
			)
		)
		(property "MPN" "CR0402-FX-4992GLF"
			(at 0 0 0)
			(layer "B.Fab")
			(hide yes)
			(effects
				(font
					(size 1 1)
					(thickness 0.15)
				)
				(justify mirror)
			)
		)
		(property "Manufacturer" "Bourns"
			(at 0 0 0)
			(layer "B.Fab")
			(hide yes)
			(effects
				(font
					(size 1 1)
					(thickness 0.15)
				)
				(justify mirror)
			)
		)
		(property "Public" ""
			(at 0 0 0)
			(layer "B.Fab")
			(hide yes)
			(effects
				(font
					(size 1 1)
					(thickness 0.15)
				)
				(justify mirror)
			)
		)
		(property "Tolerance" "1%"
			(at 0 0 0)
			(layer "B.Fab")
			(hide yes)
			(effects
				(font
					(size 1 1)
					(thickness 0.15)
				)
				(justify mirror)
			)
		)
		(property "Val" "49k9"
			(at 0 0 0)
			(layer "B.Fab")
			(hide yes)
			(effects
				(font
					(size 1 1)
					(thickness 0.15)
				)
				(justify mirror)
			)
		)
		(sheetname "/Memory/")
		(sheetfile "memory.kicad_sch")
		(attr smd)
		(fp_rect
			(start -0.925 0.47)
			(end 0.925 -0.47)
			(stroke
				(width 0.05)
				(type default)
			)
			(fill no)
			(layer "B.CrtYd")
		)
		(fp_rect
			(start -0.5 0.25)
			(end 0.5 -0.25)
			(stroke
				(width 0.15)
				(type solid)
			)
			(fill no)
			(layer "B.Fab")
		)
		(fp_text user "License: Apache-2.0"
			(at -0.95 -5.169 180)
			(layer "B.Fab")
			(effects
				(font
					(size 0.7 0.7)
					(thickness 0.15)
				)
				(justify left bottom mirror)
			)
		)
		(fp_text user "Author: Antmicro"
			(at -0.95 -4.169 180)
			(layer "B.Fab")
			(effects
				(font
					(size 0.7 0.7)
					(thickness 0.15)
				)
				(justify left bottom mirror)
			)
		)
		(fp_text user "${REFERENCE}"
			(at -0.95 -3.168 180)
			(layer "B.Fab")
			(effects
				(font
					(size 0.7 0.7)
					(thickness 0.15)
				)
				(justify left bottom mirror)
			)
		)
		(pad "1" smd roundrect
			(at -0.48 0)
			(size 0.59 0.64)
			(layers "B.Cu" "B.Mask" "B.Paste")
			(roundrect_rratio 0.25)
			(net 248 "/FPGA MSSIO/EMMC.DAT2")
			(pintype "passive")
		)
		(pad "2" smd roundrect
			(at 0.48 0)
			(size 0.59 0.64)
			(layers "B.Cu" "B.Mask" "B.Paste")
			(roundrect_rratio 0.25)
			(net 137 "SD_VDD")
			(pintype "passive")
		)
	)
	(footprint "antmicro-footprints:C_0402_1005Metric"
		(layer "B.Cu")
		(at 216.615 144.05)
		(descr "Capacitor SMD 0402")
		(tags "capacitor SMD 0402")
		(property "Reference" "C179"
			(at -1.795 1.22 180)
			(layer "B.SilkS")
			(effects
				(font
					(size 0.7 0.7)
					(thickness 0.15)
				)
				(justify right bottom mirror)
			)
		)
		(property "Value" "C_1u_0402"
			(at -1.022927 -2.155213 0)
			(layer "B.Fab")
			(hide yes)
			(effects
				(font
					(size 0.7 0.7)
					(thickness 0.15)
				)
				(justify right bottom mirror)
			)
		)
		(property "Datasheet" "https://product.tdk.com/en/search/capacitor/ceramic/mlcc/info?part_no=C1005X6S1A105K050BC"
			(at 0 0 0)
			(layer "F.Fab")
			(hide yes)
			(effects
				(font
					(size 1.27 1.27)
					(thickness 0.15)
				)
			)
		)
		(property "Description" "SMD Multilayer Ceramic Capacitor, 1 µF, 10 V, 0402 [1005 Metric], ± 10%, X6S, C"
			(at 0 0 0)
			(layer "F.Fab")
			(hide yes)
			(effects
				(font
					(size 1.27 1.27)
					(thickness 0.15)
				)
			)
		)
		(property "Author" "Antmicro"
			(at 0 0 0)
			(layer "B.Fab")
			(hide yes)
			(effects
				(font
					(size 1 1)
					(thickness 0.15)
				)
				(justify mirror)
			)
		)
		(property "Dielectric" ""
			(at 0 0 0)
			(layer "B.Fab")
			(hide yes)
			(effects
				(font
					(size 1 1)
					(thickness 0.15)
				)
				(justify mirror)
			)
		)
		(property "License" "Apache-2.0"
			(at 0 0 0)
			(layer "B.Fab")
			(hide yes)
			(effects
				(font
					(size 1 1)
					(thickness 0.15)
				)
				(justify mirror)
			)
		)
		(property "MPN" "C1005X6S1A105K050BC"
			(at 0 0 0)
			(layer "B.Fab")
			(hide yes)
			(effects
				(font
					(size 1 1)
					(thickness 0.15)
				)
				(justify mirror)
			)
		)
		(property "Manufacturer" "TDK"
			(at 0 0 0)
			(layer "B.Fab")
			(hide yes)
			(effects
				(font
					(size 1 1)
					(thickness 0.15)
				)
				(justify mirror)
			)
		)
		(property "Public" ""
			(at 0 0 0)
			(layer "B.Fab")
			(hide yes)
			(effects
				(font
					(size 1 1)
					(thickness 0.15)
				)
				(justify mirror)
			)
		)
		(property "Val" "1u"
			(at 0 0 0)
			(layer "B.Fab")
			(hide yes)
			(effects
				(font
					(size 1 1)
					(thickness 0.15)
				)
				(justify mirror)
			)
		)
		(property "Voltage" ""
			(at 0 0 0)
			(layer "B.Fab")
			(hide yes)
			(effects
				(font
					(size 1 1)
					(thickness 0.15)
				)
				(justify mirror)
			)
		)
		(sheetname "/USB/")
		(sheetfile "usb.kicad_sch")
		(attr smd)
		(fp_rect
			(start -0.925 0.47)
			(end 0.925 -0.47)
			(stroke
				(width 0.05)
				(type default)
			)
			(fill no)
			(layer "B.CrtYd")
		)
		(fp_line
			(start -0.494 -0.248)
			(end -0.494 0.25)
			(stroke
				(width 0.15)
				(type solid)
			)
			(layer "B.Fab")
		)
		(fp_line
			(start -0.494 0.25)
			(end 0.504 0.25)
			(stroke
				(width 0.15)
				(type solid)
			)
			(layer "B.Fab")
		)
		(fp_line
			(start 0.504 -0.248)
			(end -0.494 -0.248)
			(stroke
				(width 0.15)
				(type solid)
			)
			(layer "B.Fab")
		)
		(fp_line
			(start 0.504 0.25)
			(end 0.504 -0.248)
			(stroke
				(width 0.15)
				(type solid)
			)
			(layer "B.Fab")
		)
		(fp_text user "Author: Antmicro"
			(at -0.939 -3.399 180)
			(layer "B.Fab")
			(effects
				(font
					(size 0.7 0.7)
					(thickness 0.15)
				)
				(justify left bottom mirror)
			)
		)
		(fp_text user "License: Apache-2.0"
			(at -0.939 -5.799 180)
			(layer "B.Fab")
			(effects
				(font
					(size 0.7 0.7)
					(thickness 0.15)
				)
				(justify left bottom mirror)
			)
		)
		(fp_text user "${REFERENCE}"
			(at -0.939 -4.599 180)
			(layer "B.Fab")
			(effects
				(font
					(size 0.7 0.7)
					(thickness 0.15)
				)
				(justify left bottom mirror)
			)
		)
		(pad "1" smd roundrect
			(at -0.48 0)
			(size 0.59 0.64)
			(layers "B.Cu" "B.Mask" "B.Paste")
			(roundrect_rratio 0.25)
			(net 417 "GND")
			(pintype "passive")
		)
		(pad "2" smd roundrect
			(at 0.48 0)
			(size 0.59 0.64)
			(layers "B.Cu" "B.Mask" "B.Paste")
			(roundrect_rratio 0.25)
			(net 153 "/USB/VDD33")
			(pintype "passive")
		)
	)
	(footprint "antmicro-footprints:C_0402_1005Metric"
		(layer "B.Cu")
		(at 212.415 141.15 -90)
		(descr "Capacitor SMD 0402")
		(tags "capacitor SMD 0402")
		(property "Reference" "C180"
			(at -3.6 -0.435 90)
			(layer "B.SilkS")
			(effects
				(font
					(size 0.7 0.7)
					(thickness 0.15)
				)
				(justify left bottom mirror)
			)
		)
		(property "Value" "C_1u_0402"
			(at -1.022927 -2.155213 90)
			(layer "B.Fab")
			(hide yes)
			(effects
				(font
					(size 0.7 0.7)
					(thickness 0.15)
				)
				(justify left bottom mirror)
			)
		)
		(property "Datasheet" "https://product.tdk.com/en/search/capacitor/ceramic/mlcc/info?part_no=C1005X6S1A105K050BC"
			(at 0 0 270)
			(layer "F.Fab")
			(hide yes)
			(effects
				(font
					(size 1.27 1.27)
					(thickness 0.15)
				)
			)
		)
		(property "Description" "SMD Multilayer Ceramic Capacitor, 1 µF, 10 V, 0402 [1005 Metric], ± 10%, X6S, C"
			(at 0 0 270)
			(layer "F.Fab")
			(hide yes)
			(effects
				(font
					(size 1.27 1.27)
					(thickness 0.15)
				)
			)
		)
		(property "Author" "Antmicro"
			(at 71.265 353.565 0)
			(layer "B.Fab")
			(hide yes)
			(effects
				(font
					(size 1 1)
					(thickness 0.15)
				)
				(justify mirror)
			)
		)
		(property "Dielectric" ""
			(at 71.265 353.565 0)
			(layer "B.Fab")
			(hide yes)
			(effects
				(font
					(size 1 1)
					(thickness 0.15)
				)
				(justify mirror)
			)
		)
		(property "License" "Apache-2.0"
			(at 71.265 353.565 0)
			(layer "B.Fab")
			(hide yes)
			(effects
				(font
					(size 1 1)
					(thickness 0.15)
				)
				(justify mirror)
			)
		)
		(property "MPN" "C1005X6S1A105K050BC"
			(at 71.265 353.565 0)
			(layer "B.Fab")
			(hide yes)
			(effects
				(font
					(size 1 1)
					(thickness 0.15)
				)
				(justify mirror)
			)
		)
		(property "Manufacturer" "TDK"
			(at 71.265 353.565 0)
			(layer "B.Fab")
			(hide yes)
			(effects
				(font
					(size 1 1)
					(thickness 0.15)
				)
				(justify mirror)
			)
		)
		(property "Public" ""
			(at 71.265 353.565 0)
			(layer "B.Fab")
			(hide yes)
			(effects
				(font
					(size 1 1)
					(thickness 0.15)
				)
				(justify mirror)
			)
		)
		(property "Val" "1u"
			(at 71.265 353.565 0)
			(layer "B.Fab")
			(hide yes)
			(effects
				(font
					(size 1 1)
					(thickness 0.15)
				)
				(justify mirror)
			)
		)
		(property "Voltage" ""
			(at 71.265 353.565 0)
			(layer "B.Fab")
			(hide yes)
			(effects
				(font
					(size 1 1)
					(thickness 0.15)
				)
				(justify mirror)
			)
		)
		(sheetname "/USB/")
		(sheetfile "usb.kicad_sch")
		(attr smd)
		(fp_rect
			(start -0.925 0.47)
			(end 0.925 -0.47)
			(stroke
				(width 0.05)
				(type default)
			)
			(fill no)
			(layer "B.CrtYd")
		)
		(fp_line
			(start -0.494 0.25)
			(end 0.504 0.25)
			(stroke
				(width 0.15)
				(type solid)
			)
			(layer "B.Fab")
		)
		(fp_line
			(start 0.504 0.25)
			(end 0.504 -0.248)
			(stroke
				(width 0.15)
				(type solid)
			)
			(layer "B.Fab")
		)
		(fp_line
			(start -0.494 -0.248)
			(end -0.494 0.25)
			(stroke
				(width 0.15)
				(type solid)
			)
			(layer "B.Fab")
		)
		(fp_line
			(start 0.504 -0.248)
			(end -0.494 -0.248)
			(stroke
				(width 0.15)
				(type solid)
			)
			(layer "B.Fab")
		)
		(fp_text user "License: Apache-2.0"
			(at -0.939 -5.799 90)
			(layer "B.Fab")
			(effects
				(font
					(size 0.7 0.7)
					(thickness 0.15)
				)
				(justify left bottom mirror)
			)
		)
		(fp_text user "${REFERENCE}"
			(at -0.939 -4.599 90)
			(layer "B.Fab")
			(effects
				(font
					(size 0.7 0.7)
					(thickness 0.15)
				)
				(justify left bottom mirror)
			)
		)
		(fp_text user "Author: Antmicro"
			(at -0.939 -3.399 90)
			(layer "B.Fab")
			(effects
				(font
					(size 0.7 0.7)
					(thickness 0.15)
				)
				(justify left bottom mirror)
			)
		)
		(pad "1" smd roundrect
			(at -0.48 0 270)
			(size 0.59 0.64)
			(layers "B.Cu" "B.Mask" "B.Paste")
			(roundrect_rratio 0.25)
			(net 417 "GND")
			(pintype "passive")
		)
		(pad "2" smd roundrect
			(at 0.48 0 270)
			(size 0.59 0.64)
			(layers "B.Cu" "B.Mask" "B.Paste")
			(roundrect_rratio 0.25)
			(net 48 "+1V8")
			(pintype "passive")
		)
	)
	(footprint "antmicro-footprints:C_0402_1005Metric"
		(layer "B.Cu")
		(at 179.1 140.9675)
		(descr "Capacitor SMD 0402")
		(tags "capacitor SMD 0402")
		(property "Reference" "C85"
			(at 9.05 9.8575 180)
			(layer "B.SilkS")
			(effects
				(font
					(size 0.7 0.7)
					(thickness 0.15)
				)
				(justify right bottom mirror)
			)
		)
		(property "Value" "C_22u_0402"
			(at -1.022927 -2.155213 0)
			(layer "B.Fab")
			(hide yes)
			(effects
				(font
					(size 0.7 0.7)
					(thickness 0.15)
				)
				(justify right bottom mirror)
			)
		)
		(property "Datasheet" "https://www.murata.com/products/productdetail?partno=GRM158R60J226ME01%23"
			(at 0 0 0)
			(layer "F.Fab")
			(hide yes)
			(effects
				(font
					(size 1.27 1.27)
					(thickness 0.15)
				)
			)
		)
		(property "Description" "SMD Multilayer Ceramic Capacitor, 22 uF, 4 V, 0402 [1005 Metric], X6S"
			(at 0 0 0)
			(layer "F.Fab")
			(hide yes)
			(effects
				(font
					(size 1.27 1.27)
					(thickness 0.15)
				)
			)
		)
		(property "Author" "Antmicro"
			(at 0 0 0)
			(layer "B.Fab")
			(hide yes)
			(effects
				(font
					(size 1 1)
					(thickness 0.15)
				)
				(justify mirror)
			)
		)
		(property "Dielectric" ""
			(at 0 0 0)
			(layer "B.Fab")
			(hide yes)
			(effects
				(font
					(size 1 1)
					(thickness 0.15)
				)
				(justify mirror)
			)
		)
		(property "License" "Apache-2.0"
			(at 0 0 0)
			(layer "B.Fab")
			(hide yes)
			(effects
				(font
					(size 1 1)
					(thickness 0.15)
				)
				(justify mirror)
			)
		)
		(property "MPN" "GRM158R60J226ME01D"
			(at 0 0 0)
			(layer "B.Fab")
			(hide yes)
			(effects
				(font
					(size 1 1)
					(thickness 0.15)
				)
				(justify mirror)
			)
		)
		(property "Manufacturer" "Murata"
			(at 0 0 0)
			(layer "B.Fab")
			(hide yes)
			(effects
				(font
					(size 1 1)
					(thickness 0.15)
				)
				(justify mirror)
			)
		)
		(property "Public" ""
			(at 0 0 0)
			(layer "B.Fab")
			(hide yes)
			(effects
				(font
					(size 1 1)
					(thickness 0.15)
				)
				(justify mirror)
			)
		)
		(property "Val" "22u"
			(at 0 0 0)
			(layer "B.Fab")
			(hide yes)
			(effects
				(font
					(size 1 1)
					(thickness 0.15)
				)
				(justify mirror)
			)
		)
		(property "Voltage" ""
			(at 0 0 0)
			(layer "B.Fab")
			(hide yes)
			(effects
				(font
					(size 1 1)
					(thickness 0.15)
				)
				(justify mirror)
			)
		)
		(sheetname "/Supply/")
		(sheetfile "supply.kicad_sch")
		(attr smd)
		(fp_rect
			(start -0.925 0.47)
			(end 0.925 -0.47)
			(stroke
				(width 0.05)
				(type default)
			)
			(fill no)
			(layer "B.CrtYd")
		)
		(fp_line
			(start -0.494 -0.248)
			(end -0.494 0.25)
			(stroke
				(width 0.15)
				(type solid)
			)
			(layer "B.Fab")
		)
		(fp_line
			(start -0.494 0.25)
			(end 0.504 0.25)
			(stroke
				(width 0.15)
				(type solid)
			)
			(layer "B.Fab")
		)
		(fp_line
			(start 0.504 -0.248)
			(end -0.494 -0.248)
			(stroke
				(width 0.15)
				(type solid)
			)
			(layer "B.Fab")
		)
		(fp_line
			(start 0.504 0.25)
			(end 0.504 -0.248)
			(stroke
				(width 0.15)
				(type solid)
			)
			(layer "B.Fab")
		)
		(fp_text user "Author: Antmicro"
			(at -0.939 -3.399 180)
			(layer "B.Fab")
			(effects
				(font
					(size 0.7 0.7)
					(thickness 0.15)
				)
				(justify left bottom mirror)
			)
		)
		(fp_text user "${REFERENCE}"
			(at -0.939 -4.599 180)
			(layer "B.Fab")
			(effects
				(font
					(size 0.7 0.7)
					(thickness 0.15)
				)
				(justify left bottom mirror)
			)
		)
		(fp_text user "License: Apache-2.0"
			(at -0.939 -5.799 180)
			(layer "B.Fab")
			(effects
				(font
					(size 0.7 0.7)
					(thickness 0.15)
				)
				(justify left bottom mirror)
			)
		)
		(pad "1" smd roundrect
			(at -0.48 0)
			(size 0.59 0.64)
			(layers "B.Cu" "B.Mask" "B.Paste")
			(roundrect_rratio 0.25)
			(net 417 "GND")
			(pintype "passive")
		)
		(pad "2" smd roundrect
			(at 0.48 0)
			(size 0.59 0.64)
			(layers "B.Cu" "B.Mask" "B.Paste")
			(roundrect_rratio 0.25)
			(net 90 "+5V")
			(pintype "passive")
		)
	)
)
